# TIMECARD (Time Appliance Project (Time Card)) — schematic netlist excerpt (pin names and nets, part order shuffled) for the footprints in the layout excerpt that follows; sources: Cadence DE-HDL packaged netlist, KiCad conversion of R4006-B0001-02_R01.brd

C9  CAPACITOR  10UF 25V 20%  pkg SMC_0805R_H057  page 27 : \1\ = XP12R0V ; \2\ = SG
R22  RESISTOR  0OHM -  pkg SMC_0402R_H016  page 9 : \1\ = CARD_PRESENT ; \2\ = UNNAMED_3_CONN64PGF_I61_PRSNT21

(kicad_pcb
	(version 20260206)
	(generator "pcbnew")
	(generator_version "10.0")
	(general
		(thickness 1.6)
		(legacy_teardrops no)
	)
	(paper "A4")
	(title_block
		(title "timecard-production-celestica-r4006 — R4006-B0001-02_R01.brd")
		(comment 1 "Time Appliance Project (Time Card) / footprints 257-258 of 1113")
	)
	(layers
		(0 "F.Cu" signal "TOP")
		(4 "In1.Cu" signal "L02_GND1")
		(6 "In2.Cu" signal "L03_SIG1")
		(8 "In3.Cu" signal "L04_GND2")
		(10 "In4.Cu" signal "L05_VCC1")
		(12 "In5.Cu" signal "L06_VCC2")
		(14 "In6.Cu" signal "L07_GND3")
		(16 "In7.Cu" signal "L08_SIG2")
		(18 "In8.Cu" signal "L09_GND4")
		(2 "B.Cu" signal "BOTTOM")
		(9 "F.Adhes" user "F.Adhesive")
		(11 "B.Adhes" user "B.Adhesive")
		(13 "F.Paste" user "Package Geometry/Pastemask Top")
		(15 "B.Paste" user "Package Geometry/Pastemask Bottom")
		(5 "F.SilkS" user "Ref Des/Silkscreen Top")
		(7 "B.SilkS" user "Ref Des/Silkscreen Bottom")
		(1 "F.Mask" user "Board Geometry/Soldermask Top")
		(3 "B.Mask" user "Board Geometry/Soldermask Bottom")
		(17 "Dwgs.User" user "User.Drawings")
		(19 "Cmts.User" user "User.Comments")
		(21 "Eco1.User" user "User.Eco1")
		(23 "Eco2.User" user "User.Eco2")
		(25 "Edge.Cuts" user "Board Geometry/Outline")
		(27 "Margin" user)
		(31 "F.CrtYd" user "Package Geometry/Place Bound Top")
		(29 "B.CrtYd" user "Package Geometry/Place Bound Bottom")
		(35 "F.Fab" user "Ref Des/Assembly Top")
		(33 "B.Fab" user "Ref Des/Assembly Bottom")
	)
	(footprint ""
		(layer "F.Cu")
		(at 63.784988 -15.367 -90)
		(property "Reference" "R22"
			(at -2.413 -0.038862 90)
			(unlocked yes)
			(layer "F.SilkS")
			(effects
				(font
					(size 0.7874 0.5842)
					(thickness 0.1524)
				)
			)
		)
		(property "Value" "VAL*"
			(at 0.02032 2.13233 270)
			(unlocked yes)
			(layer "F.Fab")
			(hide yes)
			(effects
				(font
					(size 0.7874 0.5842)
					(thickness 0.1524)
				)
			)
		)
		(property "Tolerance" "TOL*"
			(at 0.044704 3.05435 270)
			(unlocked yes)
			(layer "Cmts.User")
			(hide yes)
			(effects
				(font
					(size 0.7874 0.5842)
					(thickness 0.1524)
				)
			)
		)
		(property "User Part Number" "PARTNUM*"
			(at 0.02032 4.024884 270)
			(unlocked yes)
			(layer "Cmts.User")
			(hide yes)
			(effects
				(font
					(size 0.7874 0.5842)
					(thickness 0.1524)
				)
			)
		)
		(property "Device Type" "RESISTOR-G155-100R0-J0,0OHM,-"
			(at 0.008382 1.210564 270)
			(unlocked yes)
			(layer "F.Fab")
			(hide yes)
			(effects
				(font
					(size 0.7874 0.5842)
					(thickness 0.1524)
				)
			)
		)
		(duplicate_pad_numbers_are_jumpers no)
		(fp_line
			(start -1.143 0.5588)
			(end 1.143 0.5588)
			(stroke
				(width 0.1)
				(type default)
			)
			(layer "F.SilkS")
		)
		(fp_line
			(start 1.143 0.5588)
			(end 1.143 -0.5588)
			(stroke
				(width 0.1)
				(type default)
			)
			(layer "F.SilkS")
		)
		(fp_line
			(start -1.143 -0.5588)
			(end -1.143 0.5588)
			(stroke
				(width 0.1)
				(type default)
			)
			(layer "F.SilkS")
		)
		(fp_line
			(start 1.143 -0.5588)
			(end -1.143 -0.5588)
			(stroke
				(width 0.1)
				(type default)
			)
			(layer "F.SilkS")
		)
		(fp_rect
			(start -1.143 -0.5588)
			(end 1.143 0.5588)
			(stroke
				(width 0)
				(type default)
			)
			(fill no)
			(layer "F.CrtYd")
		)
		(fp_line
			(start -0.508 0.3048)
			(end 0.508 0.3048)
			(stroke
				(width 0.1)
				(type default)
			)
			(layer "F.Fab")
		)
		(fp_line
			(start 0.508 0.3048)
			(end 0.508 -0.3048)
			(stroke
				(width 0.1)
				(type default)
			)
			(layer "F.Fab")
		)
		(fp_line
			(start -0.508 -0.3048)
			(end -0.508 0.3048)
			(stroke
				(width 0.1)
				(type default)
			)
			(layer "F.Fab")
		)
		(fp_line
			(start 0.508 -0.3048)
			(end -0.508 -0.3048)
			(stroke
				(width 0.1)
				(type default)
			)
			(layer "F.Fab")
		)
		(pad "1" smd rect
			(at -0.5334 0 270)
			(size 0.7112 0.6096)
			(layers "F.Cu" "F.Mask" "F.Paste")
			(net "CARD_PRESENT")
		)
		(pad "2" smd rect
			(at 0.5334 0 270)
			(size 0.7112 0.6096)
			(layers "F.Cu" "F.Mask" "F.Paste")
			(net "UNNAMED_3_CONN64PGF_I61_PRSNT21")
		)
		(zone
			(layer "F.Cu")
			(hatch none 0.5)
			(connect_pads
				(clearance 0)
			)
			(min_thickness 0.25)
			(keepout
				(tracks allowed)
				(vias not_allowed)
				(pads allowed)
				(copperpour not_allowed)
				(footprints allowed)
			)
			(placement
				(enabled no)
				(sheetname "")
			)
			(fill
				(thermal_gap 0.5)
				(thermal_bridge_width 0.5)
				(island_removal_mode 0)
			)
			(polygon
				(pts
					(xy 64.089788 -15.4432) (xy 63.480188 -15.4432) (xy 63.480188 -15.2908) (xy 64.089788 -15.2908)
				)
			)
		)
	)
	(footprint ""
		(layer "F.Cu")
		(at 135.5344 -94.107 90)
		(property "Reference" "C9"
			(at -2.921 0.01397 90)
			(unlocked yes)
			(layer "F.SilkS")
			(effects
				(font
					(size 0.7874 0.5842)
					(thickness 0.1524)
				)
			)
		)
		(property "Value" "VAL*"
			(at 0.0762 3.134106 90)
			(unlocked yes)
			(layer "F.Fab")
			(hide yes)
			(effects
				(font
					(size 0.7874 0.5842)
					(thickness 0.1524)
				)
			)
		)
		(property "Device Type" "CAPACITOR-G107-0F106-EM,10UF,2A"
			(at 0.0508 2.194306 90)
			(unlocked yes)
			(layer "F.Fab")
			(hide yes)
			(effects
				(font
					(size 0.7874 0.5842)
					(thickness 0.1524)
				)
			)
		)
		(property "User Part Number" "PARTNUM*"
			(at 0.1016 5.013706 90)
			(unlocked yes)
			(layer "Cmts.User")
			(hide yes)
			(effects
				(font
					(size 0.7874 0.5842)
					(thickness 0.1524)
				)
			)
		)
		(property "Tolerance" "TOL*"
			(at 0.0762 4.048506 90)
			(unlocked yes)
			(layer "Cmts.User")
			(hide yes)
			(effects
				(font
					(size 0.7874 0.5842)
					(thickness 0.1524)
				)
			)
		)
		(duplicate_pad_numbers_are_jumpers no)
		(fp_line
			(start 1.5748 -0.9398)
			(end -1.5748 -0.9398)
			(stroke
				(width 0.1)
				(type default)
			)
			(layer "F.SilkS")
		)
		(fp_line
			(start -1.5748 -0.9398)
			(end -1.5748 0.9398)
			(stroke
				(width 0.1)
				(type default)
			)
			(layer "F.SilkS")
		)
		(fp_line
			(start 1.5748 0.9398)
			(end 1.5748 -0.9398)
			(stroke
				(width 0.1)
				(type default)
			)
			(layer "F.SilkS")
		)
		(fp_line
			(start -1.5748 0.9398)
			(end 1.5748 0.9398)
			(stroke
				(width 0.1)
				(type default)
			)
			(layer "F.SilkS")
		)
		(fp_rect
			(start 1.5748 0.9398)
			(end -1.5748 -0.9398)
			(stroke
				(width 0)
				(type default)
			)
			(fill no)
			(layer "F.CrtYd")
		)
		(fp_line
			(start 1.016 -0.635)
			(end -1.016 -0.635)
			(stroke
				(width 0.1)
				(type default)
			)
			(layer "F.Fab")
		)
		(fp_line
			(start -1.016 -0.635)
			(end -1.016 0.635)
			(stroke
				(width 0.1)
				(type default)
			)
			(layer "F.Fab")
		)
		(fp_line
			(start 1.016 0.635)
			(end 1.016 -0.635)
			(stroke
				(width 0.1)
				(type default)
			)
			(layer "F.Fab")
		)
		(fp_line
			(start -1.016 0.635)
			(end 1.016 0.635)
			(stroke
				(width 0.1)
				(type default)
			)
			(layer "F.Fab")
		)
		(pad "1" smd rect
			(at -0.8382 0 90)
			(size 0.9652 1.3716)
			(layers "F.Cu" "F.Mask" "F.Paste")
			(net "XP12R0V")
		)
		(pad "2" smd rect
			(at 0.8382 0 90)
			(size 0.9652 1.3716)
			(layers "F.Cu" "F.Mask" "F.Paste")
			(net "SG")
		)
		(zone
			(layer "F.Cu")
			(hatch none 0.5)
			(connect_pads
				(clearance 0)
			)
			(min_thickness 0.25)
			(keepout
				(tracks allowed)
				(vias not_allowed)
				(pads allowed)
				(copperpour not_allowed)
				(footprints allowed)
			)
			(placement
				(enabled no)
				(sheetname "")
			)
			(fill
				(thermal_gap 0.5)
				(thermal_bridge_width 0.5)
				(island_removal_mode 0)
			)
			(polygon
				(pts
					(xy 136.1694 -94.3356) (xy 134.8994 -94.3356) (xy 134.8994 -93.8784) (xy 136.1694 -93.8784)
				)
			)
		)
	)
)
